# BASEBOARD_FAB2 (Tioga Pass) — schematic netlist excerpt (pin names and nets, part order shuffled) for the footprints in the layout excerpt that follows; sources: Cadence DE-HDL packaged netlist, KiCad conversion of Wiwynn_Tioga_Pass_MB.brd

R25W60  RES  100.0K 1% CHIP  pkg 0402  page 145 : A = CLK_100M_BMC_PE_R_DN ; B = GND
C6W10  CAP_A  0.1UF 16V 10% X7R  pkg 0402V  page 176 : A = P3V3_STBY ; B = GND
R7F27  RES  1.00K 1% CHIP  pkg 0402  page 215 : A = P3V3_STBY ; B = IRQ_PVDDQ_ABC_VRHOT_LVT3_R_N

(kicad_pcb
	(version 20260206)
	(generator "pcbnew")
	(generator_version "10.0")
	(general
		(thickness 1.6)
		(legacy_teardrops no)
	)
	(paper "A4")
	(title_block
		(title "Wiwynn_Tioga_Pass_MB.brd")
		(comment 1 "Tioga Pass / footprints 1852-1854 of 4770")
	)
	(layers
		(0 "F.Cu" signal "TOP")
		(4 "In1.Cu" signal "L2GND")
		(6 "In2.Cu" signal "L3")
		(8 "In3.Cu" signal "L4GND")
		(10 "In4.Cu" signal "L5")
		(12 "In5.Cu" signal "L6GND")
		(14 "In6.Cu" signal "L7VCC")
		(16 "In7.Cu" signal "L8VCC")
		(18 "In8.Cu" signal "L9GND")
		(20 "In9.Cu" signal "L10")
		(22 "In10.Cu" signal "L11GND")
		(24 "In11.Cu" signal "L12")
		(26 "In12.Cu" signal "L13GND")
		(2 "B.Cu" signal "BOTTOM")
		(9 "F.Adhes" user "F.Adhesive")
		(11 "B.Adhes" user "B.Adhesive")
		(13 "F.Paste" user "Package Geometry/Pastemask Top")
		(15 "B.Paste" user "Package Geometry/Pastemask Bottom")
		(5 "F.SilkS" user "Ref Des/Silkscreen Top")
		(7 "B.SilkS" user "Ref Des/Silkscreen Bottom")
		(1 "F.Mask" user "Board Geometry/Soldermask Top")
		(3 "B.Mask" user "Board Geometry/Soldermask Bottom")
		(17 "Dwgs.User" user "User.Drawings")
		(19 "Cmts.User" user "User.Comments")
		(21 "Eco1.User" user "User.Eco1")
		(23 "Eco2.User" user "User.Eco2")
		(25 "Edge.Cuts" user "Board Geometry/Outline")
		(27 "Margin" user)
		(31 "F.CrtYd" user "Package Geometry/Place Bound Top")
		(29 "B.CrtYd" user "Package Geometry/Place Bound Bottom")
		(35 "F.Fab" user "Ref Des/Assembly Top")
		(33 "B.Fab" user "Ref Des/Assembly Bottom")
	)
	(footprint ""
		(layer "F.Cu")
		(at 337.947 -19.7612 90)
		(property "Reference" "R7F27"
			(at 0 0 90)
			(layer "F.SilkS")
			(hide yes)
			(effects
				(font
					(size 1.27 1.27)
				)
			)
		)
		(property "Value" ""
			(at 0 0 90)
			(layer "F.Fab")
			(effects
				(font
					(size 1.27 1.27)
				)
			)
		)
		(duplicate_pad_numbers_are_jumpers no)
		(fp_poly
			(pts
				(xy -0.2794 -0.1016) (xy 0.2794 -0.1016) (xy 0.2794 0.9906) (xy -0.2794 0.9906)
			)
			(stroke
				(width 0)
				(type default)
			)
			(fill no)
			(layer "F.CrtYd")
		)
		(fp_line
			(start 0.2794 -0.1016)
			(end -0.2794 -0.1016)
			(stroke
				(width 0.1)
				(type default)
			)
			(layer "F.Fab")
		)
		(fp_line
			(start -0.2794 -0.1016)
			(end -0.2794 0.9906)
			(stroke
				(width 0.1)
				(type default)
			)
			(layer "F.Fab")
		)
		(fp_line
			(start 0.2794 0.9906)
			(end 0.2794 -0.1016)
			(stroke
				(width 0.1)
				(type default)
			)
			(layer "F.Fab")
		)
		(fp_line
			(start -0.2794 0.9906)
			(end 0.2794 0.9906)
			(stroke
				(width 0.1)
				(type default)
			)
			(layer "F.Fab")
		)
		(pad "1" smd rect
			(at 0 0 90)
			(size 0.508 0.508)
			(layers "F.Cu" "F.Mask" "F.Paste")
			(net "P3V3_STBY")
		)
		(pad "2" smd rect
			(at 0 0.889 90)
			(size 0.508 0.508)
			(layers "F.Cu" "F.Mask" "F.Paste")
			(net "IRQ_PVDDQ_ABC_VRHOT_LVT3_R_N")
		)
		(zone
			(layer "F.Cu")
			(hatch none 0.5)
			(connect_pads
				(clearance 0)
			)
			(min_thickness 0.25)
			(keepout
				(tracks allowed)
				(vias not_allowed)
				(pads allowed)
				(copperpour not_allowed)
				(footprints allowed)
			)
			(placement
				(enabled no)
				(sheetname "")
			)
			(fill
				(thermal_gap 0.5)
				(thermal_bridge_width 0.5)
				(island_removal_mode 0)
			)
			(polygon
				(pts
					(xy 338.201 -19.5072) (xy 338.201 -20.0152) (xy 338.582 -20.0152) (xy 338.582 -19.5072)
				)
			)
		)
		(zone
			(layer "F.Cu")
			(hatch none 0.5)
			(connect_pads
				(clearance 0)
			)
			(min_thickness 0.25)
			(keepout
				(tracks not_allowed)
				(vias allowed)
				(pads allowed)
				(copperpour not_allowed)
				(footprints allowed)
			)
			(placement
				(enabled no)
				(sheetname "")
			)
			(fill
				(thermal_gap 0.5)
				(thermal_bridge_width 0.5)
				(island_removal_mode 0)
			)
			(polygon
				(pts
					(xy 338.582 -19.5072) (xy 338.582 -20.0152) (xy 338.201 -20.0152) (xy 338.201 -19.5072)
				)
			)
		)
	)
	(footprint ""
		(layer "F.Cu")
		(at 411.892242 -47.682404 180)
		(property "Reference" "R25W60"
			(at -0.8382 -0.67818 180)
			(unlocked yes)
			(layer "F.SilkS")
			(effects
				(font
					(size 0.4064 0.254)
					(thickness 0.1524)
				)
				(justify left)
			)
		)
		(property "Value" ""
			(at 0 0 180)
			(layer "F.Fab")
			(effects
				(font
					(size 1.27 1.27)
				)
			)
		)
		(duplicate_pad_numbers_are_jumpers no)
		(fp_poly
			(pts
				(xy -0.2794 -0.1016) (xy 0.2794 -0.1016) (xy 0.2794 0.9906) (xy -0.2794 0.9906)
			)
			(stroke
				(width 0)
				(type default)
			)
			(fill no)
			(layer "F.CrtYd")
		)
		(fp_line
			(start 0.2794 0.9906)
			(end 0.2794 -0.1016)
			(stroke
				(width 0.1)
				(type default)
			)
			(layer "F.Fab")
		)
		(fp_line
			(start 0.2794 -0.1016)
			(end -0.2794 -0.1016)
			(stroke
				(width 0.1)
				(type default)
			)
			(layer "F.Fab")
		)
		(fp_line
			(start -0.2794 0.9906)
			(end 0.2794 0.9906)
			(stroke
				(width 0.1)
				(type default)
			)
			(layer "F.Fab")
		)
		(fp_line
			(start -0.2794 -0.1016)
			(end -0.2794 0.9906)
			(stroke
				(width 0.1)
				(type default)
			)
			(layer "F.Fab")
		)
		(pad "1" smd rect
			(at 0 0 180)
			(size 0.508 0.508)
			(layers "F.Cu" "F.Mask" "F.Paste")
			(net "CLK_100M_BMC_PE_R_DN")
		)
		(pad "2" smd rect
			(at 0 0.889 180)
			(size 0.508 0.508)
			(layers "F.Cu" "F.Mask" "F.Paste")
			(net "GND")
		)
		(zone
			(layer "F.Cu")
			(hatch none 0.5)
			(connect_pads
				(clearance 0)
			)
			(min_thickness 0.25)
			(keepout
				(tracks not_allowed)
				(vias allowed)
				(pads allowed)
				(copperpour not_allowed)
				(footprints allowed)
			)
			(placement
				(enabled no)
				(sheetname "")
			)
			(fill
				(thermal_gap 0.5)
				(thermal_bridge_width 0.5)
				(island_removal_mode 0)
			)
			(polygon
				(pts
					(xy 412.146242 -48.317404) (xy 411.638242 -48.317404) (xy 411.638242 -47.936404) (xy 412.146242 -47.936404)
				)
			)
		)
		(zone
			(layer "F.Cu")
			(hatch none 0.5)
			(connect_pads
				(clearance 0)
			)
			(min_thickness 0.25)
			(keepout
				(tracks allowed)
				(vias not_allowed)
				(pads allowed)
				(copperpour not_allowed)
				(footprints allowed)
			)
			(placement
				(enabled no)
				(sheetname "")
			)
			(fill
				(thermal_gap 0.5)
				(thermal_bridge_width 0.5)
				(island_removal_mode 0)
			)
			(polygon
				(pts
					(xy 412.146242 -47.936404) (xy 411.638242 -47.936404) (xy 411.638242 -48.317404) (xy 412.146242 -48.317404)
				)
			)
		)
	)
	(footprint ""
		(layer "F.Cu")
		(at 487.2228 -138.4554 180)
		(property "Reference" "C6W10"
			(at -0.8382 -0.67818 180)
			(unlocked yes)
			(layer "F.SilkS")
			(effects
				(font
					(size 0.4064 0.254)
					(thickness 0.1524)
				)
				(justify left)
			)
		)
		(property "Value" ""
			(at 0 0 180)
			(layer "F.Fab")
			(effects
				(font
					(size 1.27 1.27)
				)
			)
		)
		(duplicate_pad_numbers_are_jumpers no)
		(fp_poly
			(pts
				(xy 0.3048 -0.1016) (xy 0.3048 0.9906) (xy -0.3048 0.9906) (xy -0.3048 -0.1016)
			)
			(stroke
				(width 0)
				(type default)
			)
			(fill no)
			(layer "F.CrtYd")
		)
		(fp_line
			(start 0.3048 0.9906)
			(end 0.3048 -0.1016)
			(stroke
				(width 0.1)
				(type default)
			)
			(layer "F.Fab")
		)
		(fp_line
			(start 0.3048 -0.1016)
			(end -0.3048 -0.1016)
			(stroke
				(width 0.1)
				(type default)
			)
			(layer "F.Fab")
		)
		(fp_line
			(start -0.3048 0.9906)
			(end 0.3048 0.9906)
			(stroke
				(width 0.1)
				(type default)
			)
			(layer "F.Fab")
		)
		(fp_line
			(start -0.3048 -0.1016)
			(end -0.3048 0.9906)
			(stroke
				(width 0.1)
				(type default)
			)
			(layer "F.Fab")
		)
		(pad "1" smd rect
			(at 0 0 180)
			(size 0.508 0.508)
			(layers "F.Cu" "F.Mask" "F.Paste")
			(net "P3V3_STBY")
		)
		(pad "2" smd rect
			(at 0 0.889 180)
			(size 0.508 0.508)
			(layers "F.Cu" "F.Mask" "F.Paste")
			(net "GND")
		)
		(zone
			(layer "F.Cu")
			(hatch none 0.5)
			(connect_pads
				(clearance 0)
			)
			(min_thickness 0.25)
			(keepout
				(tracks not_allowed)
				(vias allowed)
				(pads allowed)
				(copperpour not_allowed)
				(footprints allowed)
			)
			(placement
				(enabled no)
				(sheetname "")
			)
			(fill
				(thermal_gap 0.5)
				(thermal_bridge_width 0.5)
				(island_removal_mode 0)
			)
			(polygon
				(pts
					(xy 487.4768 -139.0904) (xy 486.9688 -139.0904) (xy 486.9688 -138.7094) (xy 487.4768 -138.7094)
				)
			)
		)
		(zone
			(layer "F.Cu")
			(hatch none 0.5)
			(connect_pads
				(clearance 0)
			)
			(min_thickness 0.25)
			(keepout
				(tracks allowed)
				(vias not_allowed)
				(pads allowed)
				(copperpour not_allowed)
				(footprints allowed)
			)
			(placement
				(enabled no)
				(sheetname "")
			)
			(fill
				(thermal_gap 0.5)
				(thermal_bridge_width 0.5)
				(island_removal_mode 0)
			)
			(polygon
				(pts
					(xy 487.4768 -138.7094) (xy 486.9688 -138.7094) (xy 486.9688 -139.0904) (xy 487.4768 -139.0904)
				)
			)
		)
	)
)
